(kicad_pcb
	(version 20260206)
	(generator "pcbnew")
	(generator_version "10.0")
	(general
		(thickness 1.6)
		(legacy_teardrops no)
	)
	(paper "A4")
	(title_block
		(title "Wiwynn_Tioga_Pass_MB.brd")
		(comment 1 "Tioga Pass / footprints 1598-1602 of 4770")
	)
	(layers
		(0 "F.Cu" signal "TOP")
		(4 "In1.Cu" signal "L2GND")
		(6 "In2.Cu" signal "L3")
		(8 "In3.Cu" signal "L4GND")
		(10 "In4.Cu" signal "L5")
		(12 "In5.Cu" signal "L6GND")
		(14 "In6.Cu" signal "L7VCC")
		(16 "In7.Cu" signal "L8VCC")
		(18 "In8.Cu" signal "L9GND")
		(20 "In9.Cu" signal "L10")
		(22 "In10.Cu" signal "L11GND")
		(24 "In11.Cu" signal "L12")
		(26 "In12.Cu" signal "L13GND")
		(2 "B.Cu" signal "BOTTOM")
		(9 "F.Adhes" user "F.Adhesive")
		(11 "B.Adhes" user "B.Adhesive")
		(13 "F.Paste" user "Package Geometry/Pastemask Top")
		(15 "B.Paste" user "Package Geometry/Pastemask Bottom")
		(5 "F.SilkS" user "Ref Des/Silkscreen Top")
		(7 "B.SilkS" user "Ref Des/Silkscreen Bottom")
		(1 "F.Mask" user "Board Geometry/Soldermask Top")
		(3 "B.Mask" user "Board Geometry/Soldermask Bottom")
		(17 "Dwgs.User" user "User.Drawings")
		(19 "Cmts.User" user "User.Comments")
		(21 "Eco1.User" user "User.Eco1")
		(23 "Eco2.User" user "User.Eco2")
		(25 "Edge.Cuts" user "Board Geometry/Outline")
		(27 "Margin" user)
		(31 "F.CrtYd" user "Package Geometry/Place Bound Top")
		(29 "B.CrtYd" user "Package Geometry/Place Bound Bottom")
		(35 "F.Fab" user "Ref Des/Assembly Top")
		(33 "B.Fab" user "Ref Des/Assembly Bottom")
	)
	(footprint ""
		(layer "F.Cu")
		(at 183.0832 -75.565 -90)
		(property "Reference" "C4D20"
			(at 0 0 270)
			(layer "F.SilkS")
			(hide yes)
			(effects
				(font
					(size 1.27 1.27)
				)
			)
		)
		(property "Value" ""
			(at 0 0 270)
			(layer "F.Fab")
			(effects
				(font
					(size 1.27 1.27)
				)
			)
		)
		(duplicate_pad_numbers_are_jumpers no)
		(fp_rect
			(start 0.3048 0.9906)
			(end -0.3048 -0.1016)
			(stroke
				(width 0)
				(type default)
			)
			(fill no)
			(layer "F.CrtYd")
		)
		(fp_line
			(start -0.3048 0.9906)
			(end 0.3048 0.9906)
			(stroke
				(width 0.1)
				(type default)
			)
			(layer "F.Fab")
		)
		(fp_line
			(start 0.3048 0.9906)
			(end 0.3048 -0.1016)
			(stroke
				(width 0.1)
				(type default)
			)
			(layer "F.Fab")
		)
		(fp_line
			(start -0.3048 -0.1016)
			(end -0.3048 0.9906)
			(stroke
				(width 0.1)
				(type default)
			)
			(layer "F.Fab")
		)
		(fp_line
			(start 0.3048 -0.1016)
			(end -0.3048 -0.1016)
			(stroke
				(width 0.1)
				(type default)
			)
			(layer "F.Fab")
		)
		(pad "1" smd rect
			(at 0 0 270)
			(size 0.508 0.508)
			(layers "F.Cu" "F.Mask" "F.Paste")
			(net "VR_PVCCIN_CPU0_AVINSEN")
		)
		(pad "2" smd rect
			(at 0 0.889 270)
			(size 0.508 0.508)
			(layers "F.Cu" "F.Mask" "F.Paste")
			(net "GND")
		)
		(zone
			(layer "F.Cu")
			(hatch none 0.5)
			(connect_pads
				(clearance 0)
			)
			(min_thickness 0.25)
			(keepout
				(tracks allowed)
				(vias not_allowed)
				(pads allowed)
				(copperpour not_allowed)
				(footprints allowed)
			)
			(placement
				(enabled no)
				(sheetname "")
			)
			(fill
				(thermal_gap 0.5)
				(thermal_bridge_width 0.5)
				(island_removal_mode 0)
			)
			(polygon
				(pts
					(xy 182.4482 -75.311) (xy 182.8292 -75.311) (xy 182.8292 -75.819) (xy 182.4482 -75.819)
				)
			)
		)
		(zone
			(layer "F.Cu")
			(hatch none 0.5)
			(connect_pads
				(clearance 0)
			)
			(min_thickness 0.25)
			(keepout
				(tracks not_allowed)
				(vias allowed)
				(pads allowed)
				(copperpour not_allowed)
				(footprints allowed)
			)
			(placement
				(enabled no)
				(sheetname "")
			)
			(fill
				(thermal_gap 0.5)
				(thermal_bridge_width 0.5)
				(island_removal_mode 0)
			)
			(polygon
				(pts
					(xy 182.4482 -75.311) (xy 182.8292 -75.311) (xy 182.8292 -75.819) (xy 182.4482 -75.819)
				)
			)
		)
	)
	(footprint ""
		(layer "F.Cu")
		(at 451.85838 -33.5915 90)
		(property "Reference" "R25W37"
			(at 0 0 90)
			(layer "F.SilkS")
			(hide yes)
			(effects
				(font
					(size 1.27 1.27)
				)
			)
		)
		(property "Value" "*"
			(at 0.064008 -4.108196 90)
			(unlocked yes)
			(layer "F.Fab")
			(hide yes)
			(effects
				(font
					(size 1.27 1.016)
					(thickness 0.1524)
				)
			)
		)
		(property "Device Type" "120R2F-GP_RCL_GP-120R2F-GP,64.A"
			(at 0.064008 -5.632196 90)
			(unlocked yes)
			(layer "F.Fab")
			(hide yes)
			(effects
				(font
					(size 1.27 1.016)
					(thickness 0.1524)
				)
			)
		)
		(duplicate_pad_numbers_are_jumpers no)
		(fp_line
			(start 0.508 -0.9398)
			(end -0.508 -0.9398)
			(stroke
				(width 0.1524)
				(type default)
			)
			(layer "F.SilkS")
		)
		(fp_line
			(start -0.508 -0.9398)
			(end -0.508 0.9398)
			(stroke
				(width 0.1524)
				(type default)
			)
			(layer "F.SilkS")
		)
		(fp_rect
			(start -0.508 0.9398)
			(end 0.508 -0.9398)
			(stroke
				(width 0)
				(type default)
			)
			(fill no)
			(layer "F.CrtYd")
		)
		(fp_rect
			(start -0.508 0.9398)
			(end 0.508 -0.9398)
			(stroke
				(width 0)
				(type default)
			)
			(fill no)
			(layer "F.Fab")
		)
		(pad "1" smd custom
			(at 0 -0.4445 90)
			(size 0.1397 0.1397)
			(layers "F.Cu" "F.Mask" "F.Paste")
			(net "BMC_M_BG0")
			(options
				(clearance outline)
				(anchor circle)
			)
			(primitives
				(gr_poly
					(pts
						(arc
							(start -0.1778 -0.2794)
							(mid -0.249642 -0.249642)
							(end -0.2794 -0.1778)
						)
						(arc
							(start -0.2794 0.1778)
							(mid -0.249642 0.249642)
							(end -0.1778 0.2794)
						)
						(arc
							(start 0.1778 0.2794)
							(mid 0.249642 0.249642)
							(end 0.2794 0.1778)
						)
						(arc
							(start 0.2794 -0.1778)
							(mid 0.249642 -0.249642)
							(end 0.1778 -0.2794)
						)
					)
					(width 0)
					(fill yes)
				)
			)
		)
		(pad "2" smd custom
			(at 0 0.4445 90)
			(size 0.1397 0.1397)
			(layers "F.Cu" "F.Mask" "F.Paste")
			(net "P1V2_AUX_BMC")
			(options
				(clearance outline)
				(anchor circle)
			)
			(primitives
				(gr_poly
					(pts
						(arc
							(start -0.1778 -0.2794)
							(mid -0.249642 -0.249642)
							(end -0.2794 -0.1778)
						)
						(arc
							(start -0.2794 0.1778)
							(mid -0.249642 0.249642)
							(end -0.1778 0.2794)
						)
						(arc
							(start 0.1778 0.2794)
							(mid 0.249642 0.249642)
							(end 0.2794 0.1778)
						)
						(arc
							(start 0.2794 -0.1778)
							(mid 0.249642 -0.249642)
							(end 0.1778 -0.2794)
						)
					)
					(width 0)
					(fill yes)
				)
			)
		)
	)
	(footprint ""
		(layer "F.Cu")
		(at 348.361 -133.604 180)
		(property "Reference" "C7B6"
			(at 0 0 180)
			(layer "F.SilkS")
			(hide yes)
			(effects
				(font
					(size 1.27 1.27)
				)
			)
		)
		(property "Value" ""
			(at 0 0 180)
			(layer "F.Fab")
			(effects
				(font
					(size 1.27 1.27)
				)
			)
		)
		(duplicate_pad_numbers_are_jumpers no)
		(fp_poly
			(pts
				(xy 0.3048 -0.1016) (xy 0.3048 0.9906) (xy -0.3048 0.9906) (xy -0.3048 -0.1016)
			)
			(stroke
				(width 0)
				(type default)
			)
			(fill no)
			(layer "F.CrtYd")
		)
		(fp_line
			(start 0.3048 0.9906)
			(end 0.3048 -0.1016)
			(stroke
				(width 0.1)
				(type default)
			)
			(layer "F.Fab")
		)
		(fp_line
			(start 0.3048 -0.1016)
			(end -0.3048 -0.1016)
			(stroke
				(width 0.1)
				(type default)
			)
			(layer "F.Fab")
		)
		(fp_line
			(start -0.3048 0.9906)
			(end 0.3048 0.9906)
			(stroke
				(width 0.1)
				(type default)
			)
			(layer "F.Fab")
		)
		(fp_line
			(start -0.3048 -0.1016)
			(end -0.3048 0.9906)
			(stroke
				(width 0.1)
				(type default)
			)
			(layer "F.Fab")
		)
		(pad "1" smd rect
			(at 0 0 180)
			(size 0.508 0.508)
			(layers "F.Cu" "F.Mask" "F.Paste")
			(net "VR_FET_SW_P12V_STBY_PVPP_DEF")
		)
		(pad "2" smd rect
			(at 0 0.889 180)
			(size 0.508 0.508)
			(layers "F.Cu" "F.Mask" "F.Paste")
			(net "GND")
		)
		(zone
			(layer "F.Cu")
			(hatch none 0.5)
			(connect_pads
				(clearance 0)
			)
			(min_thickness 0.25)
			(keepout
				(tracks not_allowed)
				(vias allowed)
				(pads allowed)
				(copperpour not_allowed)
				(footprints allowed)
			)
			(placement
				(enabled no)
				(sheetname "")
			)
			(fill
				(thermal_gap 0.5)
				(thermal_bridge_width 0.5)
				(island_removal_mode 0)
			)
			(polygon
				(pts
					(xy 348.615 -134.239) (xy 348.107 -134.239) (xy 348.107 -133.858) (xy 348.615 -133.858)
				)
			)
		)
		(zone
			(layer "F.Cu")
			(hatch none 0.5)
			(connect_pads
				(clearance 0)
			)
			(min_thickness 0.25)
			(keepout
				(tracks allowed)
				(vias not_allowed)
				(pads allowed)
				(copperpour not_allowed)
				(footprints allowed)
			)
			(placement
				(enabled no)
				(sheetname "")
			)
			(fill
				(thermal_gap 0.5)
				(thermal_bridge_width 0.5)
				(island_removal_mode 0)
			)
			(polygon
				(pts
					(xy 348.615 -133.858) (xy 348.107 -133.858) (xy 348.107 -134.239) (xy 348.615 -134.239)
				)
			)
		)
	)
	(footprint ""
		(layer "F.Cu")
		(at -4.021074 -139.00531 90)
		(property "Reference" "RT5"
			(at 1.01473 0.656336 0)
			(unlocked yes)
			(layer "F.SilkS")
			(effects
				(font
					(size 0.4064 0.254)
					(thickness 0.1524)
				)
			)
		)
		(property "Value" ""
			(at 0 0 90)
			(layer "F.Fab")
			(effects
				(font
					(size 1.27 1.27)
				)
			)
		)
		(duplicate_pad_numbers_are_jumpers no)
		(fp_poly
			(pts
				(xy -0.4953 -0.2032) (xy 0.4953 -0.2032) (xy 0.4953 1.6002) (xy -0.4953 1.6002)
			)
			(stroke
				(width 0)
				(type default)
			)
			(fill no)
			(layer "F.CrtYd")
		)
		(fp_line
			(start 0.4953 -0.2032)
			(end 0.4953 1.6002)
			(stroke
				(width 0.1)
				(type default)
			)
			(layer "F.Fab")
		)
		(fp_line
			(start -0.4953 -0.2032)
			(end 0.4953 -0.2032)
			(stroke
				(width 0.1)
				(type default)
			)
			(layer "F.Fab")
		)
		(fp_line
			(start 0.4953 1.6002)
			(end -0.4953 1.6002)
			(stroke
				(width 0.1)
				(type default)
			)
			(layer "F.Fab")
		)
		(fp_line
			(start -0.4953 1.6002)
			(end -0.4953 -0.2032)
			(stroke
				(width 0.1)
				(type default)
			)
			(layer "F.Fab")
		)
		(pad "1" smd rect
			(at 0 0 90)
			(size 0.762 0.889)
			(layers "F.Cu" "F.Mask" "F.Paste")
			(net "VR_PVDDQ_KLM_PH1_BOOT")
		)
		(pad "2" smd rect
			(at 0 1.397 90)
			(size 0.762 0.889)
			(layers "F.Cu" "F.Mask" "F.Paste")
			(net "VR_PVDDQ_KLM_PH1_BOOT_R")
		)
		(zone
			(layer "F.Cu")
			(hatch none 0.5)
			(connect_pads
				(clearance 0)
			)
			(min_thickness 0.25)
			(keepout
				(tracks allowed)
				(vias not_allowed)
				(pads allowed)
				(copperpour not_allowed)
				(footprints allowed)
			)
			(placement
				(enabled no)
				(sheetname "")
			)
			(fill
				(thermal_gap 0.5)
				(thermal_bridge_width 0.5)
				(island_removal_mode 0)
			)
			(polygon
				(pts
					(xy -3.068574 -139.38631) (xy -3.576574 -139.38631) (xy -3.576574 -138.62431) (xy -3.068574 -138.62431)
				)
			)
		)
		(zone
			(layer "F.Cu")
			(hatch none 0.5)
			(connect_pads
				(clearance 0)
			)
			(min_thickness 0.25)
			(keepout
				(tracks not_allowed)
				(vias allowed)
				(pads allowed)
				(copperpour not_allowed)
				(footprints allowed)
			)
			(placement
				(enabled no)
				(sheetname "")
			)
			(fill
				(thermal_gap 0.5)
				(thermal_bridge_width 0.5)
				(island_removal_mode 0)
			)
			(polygon
				(pts
					(xy -3.068574 -138.62431) (xy -3.068574 -139.38631) (xy -3.576574 -139.38631) (xy -3.576574 -138.62431)
				)
			)
		)
	)
	(footprint ""
		(layer "F.Cu")
		(at 470.282016 -134.366)
		(property "Reference" "J9B4"
			(at -4.77012 9.83615 0)
			(unlocked yes)
			(layer "F.SilkS")
			(effects
				(font
					(size 0.7874 0.5842)
					(thickness 0.1524)
				)
				(justify left)
			)
		)
		(property "Value" ""
			(at 0 0 0)
			(layer "F.Fab")
			(effects
				(font
					(size 1.27 1.27)
				)
			)
		)
		(duplicate_pad_numbers_are_jumpers no)
		(fp_line
			(start -1.1303 -2.426208)
			(end 5.3721 -2.426208)
			(stroke
				(width 0.1524)
				(type default)
			)
			(layer "F.SilkS")
		)
		(fp_line
			(start -1.1303 10.426192)
			(end 5.3721 10.426192)
			(stroke
				(width 0.1524)
				(type default)
			)
			(layer "F.SilkS")
		)
		(fp_line
			(start -1.12903 -0.8382)
			(end -1.1303 -2.426208)
			(stroke
				(width 0.1524)
				(type default)
			)
			(layer "F.SilkS")
		)
		(fp_line
			(start -1.12903 8.838184)
			(end -1.1303 10.426192)
			(stroke
				(width 0.1524)
				(type default)
			)
			(layer "F.SilkS")
		)
		(fp_line
			(start 5.3721 -2.426208)
			(end 5.37083 -0.8382)
			(stroke
				(width 0.1524)
				(type default)
			)
			(layer "F.SilkS")
		)
		(fp_line
			(start 5.3721 10.426192)
			(end 5.37083 8.838184)
			(stroke
				(width 0.1524)
				(type default)
			)
			(layer "F.SilkS")
		)
		(fp_poly
			(pts
				(xy -2.565908 -1.155192) (xy -2.565908 -0.139192) (xy -1.295908 -0.647192)
			)
			(stroke
				(width 0)
				(type default)
			)
			(fill yes)
			(layer "F.SilkS")
		)
		(fp_poly
			(pts
				(xy -1.1303 -2.426208) (xy 5.3721 -2.426208) (xy 5.3721 10.426192) (xy -1.1303 10.426192)
			)
			(stroke
				(width 0)
				(type default)
			)
			(fill no)
			(layer "F.CrtYd")
		)
		(fp_line
			(start -1.1303 -2.426208)
			(end 5.3721 -2.426208)
			(stroke
				(width 0.1)
				(type default)
			)
			(layer "F.Fab")
		)
		(fp_line
			(start -1.1303 10.426192)
			(end -1.1303 -2.426208)
			(stroke
				(width 0.1)
				(type default)
			)
			(layer "F.Fab")
		)
		(fp_line
			(start 5.3721 -2.426208)
			(end 5.3721 10.426192)
			(stroke
				(width 0.1)
				(type default)
			)
			(layer "F.Fab")
		)
		(fp_line
			(start 5.3721 10.426192)
			(end -1.1303 10.426192)
			(stroke
				(width 0.1)
				(type default)
			)
			(layer "F.Fab")
		)
		(fp_poly
			(pts
				(xy -2.96291 -0.521462) (xy -2.96291 0.494538) (xy -1.69291 -0.013462)
			)
			(stroke
				(width 0)
				(type default)
			)
			(fill yes)
			(layer "F.Fab")
		)
		(fp_text user "9"
			(at -2.15138 6.54939 0)
			(unlocked yes)
			(layer "F.SilkS")
			(effects
				(font
					(size 0.7874 0.5842)
					(thickness 0.1524)
				)
				(justify left)
			)
		)
		(fp_text user "10"
			(at 5.673344 6.99643 0)
			(unlocked yes)
			(layer "F.SilkS")
			(effects
				(font
					(size 0.7874 0.5842)
					(thickness 0.1524)
				)
				(justify left)
			)
		)
		(fp_text user "2"
			(at 5.971286 -0.210312 0)
			(unlocked yes)
			(layer "F.SilkS")
			(effects
				(font
					(size 0.7874 0.5842)
					(thickness 0.1524)
				)
				(justify left)
			)
		)
		(fp_text user "9"
			(at -2.152142 6.550152 0)
			(unlocked yes)
			(layer "F.Fab")
			(effects
				(font
					(size 0.7874 0.5842)
					(thickness 0.1524)
				)
				(justify left)
			)
		)
		(fp_text user "10"
			(at 5.673344 6.99643 0)
			(unlocked yes)
			(layer "F.Fab")
			(effects
				(font
					(size 0.7874 0.5842)
					(thickness 0.1524)
				)
				(justify left)
			)
		)
		(fp_text user "2"
			(at 5.967222 -0.207772 0)
			(unlocked yes)
			(layer "F.Fab")
			(effects
				(font
					(size 0.7874 0.5842)
					(thickness 0.1524)
				)
				(justify left)
			)
		)
		(pad "" np_thru_hole circle
			(at 2.1209 0.999998)
			(size 0.254 0.254)
			(drill 1.016)
			(layers "*.Cu" "*.Mask")
			(clearance 0.6985)
			(thermal_gap 0.6985)
		)
		(pad "" np_thru_hole circle
			(at 2.1209 6.999986)
			(size 0.254 0.254)
			(drill 1.016)
			(layers "*.Cu" "*.Mask")
			(clearance 0.6985)
			(thermal_gap 0.6985)
		)
		(pad "1" smd rect
			(at 0 0)
			(size 2.7432 1.016)
			(layers "F.Cu" "F.Mask" "F.Paste")
			(net "JTAG_MCP_TCK_R")
		)
		(pad "2" smd rect
			(at 4.2418 0)
			(size 2.7432 1.016)
			(layers "F.Cu" "F.Mask" "F.Paste")
			(net "GND")
		)
		(pad "3" smd rect
			(at 0 1.999996)
			(size 2.7432 1.016)
			(layers "F.Cu" "F.Mask" "F.Paste")
			(net "JTAG_MCP_MUX_TDO")
		)
		(pad "4" smd rect
			(at 4.2418 1.999996)
			(size 2.7432 1.016)
			(layers "F.Cu" "F.Mask" "F.Paste")
			(net "P1V8_MCP_CPU0")
		)
		(pad "5" smd rect
			(at 0 3.999992)
			(size 2.7432 1.016)
			(layers "F.Cu" "F.Mask" "F.Paste")
			(net "JTAG_MCP_TMS_R")
		)
		(pad "6" smd rect
			(at 4.2418 3.999992)
			(size 2.7432 1.016)
			(layers "F.Cu" "F.Mask" "F.Paste")
			(net "JTAG_MCP_TRST_N")
		)
		(pad "7" smd rect
			(at 0 5.999988)
			(size 2.7432 1.016)
			(layers "F.Cu" "F.Mask" "F.Paste")
			(net "PWRGD_CPU0_G_R")
		)
		(pad "8" smd rect
			(at 4.2418 5.999988)
			(size 2.7432 1.016)
			(layers "F.Cu" "F.Mask" "F.Paste")
			(net "TP_JTAG_MCP_IO8_RSVD")
		)
		(pad "9" smd rect
			(at 0 7.999984)
			(size 2.7432 1.016)
			(layers "F.Cu" "F.Mask" "F.Paste")
			(net "JTAG_MCP_MUX_TDI")
		)
		(pad "10" smd rect
			(at 4.2418 7.999984)
			(size 2.7432 1.016)
			(layers "F.Cu" "F.Mask" "F.Paste")
			(net "GND")
		)
		(zone
			(layers "F.Cu" "B.Cu" "In1.Cu" "In2.Cu" "In3.Cu" "In4.Cu" "In5.Cu" "In6.Cu"
				"In7.Cu" "In8.Cu" "In9.Cu" "In10.Cu" "In11.Cu" "In12.Cu"
			)
			(hatch none 0.5)
			(connect_pads
				(clearance 0)
			)
			(min_thickness 0.25)
			(keepout
				(tracks allowed)
				(vias not_allowed)
				(pads allowed)
				(copperpour not_allowed)
				(footprints allowed)
			)
			(placement
				(enabled no)
				(sheetname "")
			)
			(fill
				(thermal_gap 0.5)
				(thermal_bridge_width 0.5)
				(island_removal_mode 0)
			)
			(polygon
				(pts
					(arc
						(start 473.228416 -133.366002)
						(mid 471.577416 -133.366002)
						(end 473.228416 -133.366002)
					)
				)
			)
		)
		(zone
			(layers "F.Cu" "B.Cu" "In1.Cu" "In2.Cu" "In3.Cu" "In4.Cu" "In5.Cu" "In6.Cu"
				"In7.Cu" "In8.Cu" "In9.Cu" "In10.Cu" "In11.Cu" "In12.Cu"
			)
			(hatch none 0.5)
			(connect_pads
				(clearance 0)
			)
			(min_thickness 0.25)
			(keepout
				(tracks not_allowed)
				(vias allowed)
				(pads allowed)
				(copperpour not_allowed)
				(footprints allowed)
			)
			(placement
				(enabled no)
				(sheetname "")
			)
			(fill
				(thermal_gap 0.5)
				(thermal_bridge_width 0.5)
				(island_removal_mode 0)
			)
			(polygon
				(pts
					(arc
						(start 473.228416 -133.366002)
						(mid 471.577416 -133.366002)
						(end 473.228416 -133.366002)
					)
				)
			)
		)
		(zone
			(layers "F.Cu" "B.Cu" "In1.Cu" "In2.Cu" "In3.Cu" "In4.Cu" "In5.Cu" "In6.Cu"
				"In7.Cu" "In8.Cu" "In9.Cu" "In10.Cu" "In11.Cu" "In12.Cu"
			)
			(hatch none 0.5)
			(connect_pads
				(clearance 0)
			)
			(min_thickness 0.25)
			(keepout
				(tracks allowed)
				(vias not_allowed)
				(pads allowed)
				(copperpour not_allowed)
				(footprints allowed)
			)
			(placement
				(enabled no)
				(sheetname "")
			)
			(fill
				(thermal_gap 0.5)
				(thermal_bridge_width 0.5)
				(island_removal_mode 0)
			)
			(polygon
				(pts
					(arc
						(start 473.228416 -127.366014)
						(mid 471.577416 -127.366014)
						(end 473.228416 -127.366014)
					)
				)
			)
		)
		(zone
			(layers "F.Cu" "B.Cu" "In1.Cu" "In2.Cu" "In3.Cu" "In4.Cu" "In5.Cu" "In6.Cu"
				"In7.Cu" "In8.Cu" "In9.Cu" "In10.Cu" "In11.Cu" "In12.Cu"
			)
			(hatch none 0.5)
			(connect_pads
				(clearance 0)
			)
			(min_thickness 0.25)
			(keepout
				(tracks not_allowed)
				(vias allowed)
				(pads allowed)
				(copperpour not_allowed)
				(footprints allowed)
			)
			(placement
				(enabled no)
				(sheetname "")
			)
			(fill
				(thermal_gap 0.5)
				(thermal_bridge_width 0.5)
				(island_removal_mode 0)
			)
			(polygon
				(pts
					(arc
						(start 473.228416 -127.366014)
						(mid 471.577416 -127.366014)
						(end 473.228416 -127.366014)
					)
				)
			)
		)
	)
)
